(kicad_pcb
	(version 20260206)
	(generator "pcbnew")
	(generator_version "10.0")
	(general
		(thickness 1.6)
		(legacy_teardrops no)
	)
	(paper "A4")
	(title_block
		(title "9054_F0T_PDB_BD_GPU_F_V04_1213_1550_OCP.brd")
		(comment 1 "Grand Teton / footprints 311-312 of 608")
	)
	(layers
		(0 "F.Cu" signal "TOP")
		(4 "In1.Cu" signal "GND")
		(6 "In2.Cu" signal "IN1")
		(8 "In3.Cu" signal "GND1")
		(10 "In4.Cu" signal "VCC")
		(12 "In5.Cu" signal "VCC1")
		(14 "In6.Cu" signal "GND2")
		(16 "In7.Cu" signal "IN2")
		(18 "In8.Cu" signal "GND3")
		(2 "B.Cu" signal "BOTTOM")
		(9 "F.Adhes" user "F.Adhesive")
		(11 "B.Adhes" user "B.Adhesive")
		(13 "F.Paste" user "Package Geometry/Pastemask Top")
		(15 "B.Paste" user "Package Geometry/Pastemask Bottom")
		(5 "F.SilkS" user "Ref Des/Silkscreen Top")
		(7 "B.SilkS" user "Ref Des/Silkscreen Bottom")
		(1 "F.Mask" user "Board Geometry/Soldermask Top")
		(3 "B.Mask" user "Board Geometry/Soldermask Bottom")
		(17 "Dwgs.User" user "User.Drawings")
		(19 "Cmts.User" user "User.Comments")
		(21 "Eco1.User" user "User.Eco1")
		(23 "Eco2.User" user "User.Eco2")
		(25 "Edge.Cuts" user "Board Geometry/Outline")
		(27 "Margin" user)
		(31 "F.CrtYd" user "Package Geometry/Place Bound Top")
		(29 "B.CrtYd" user "Package Geometry/Place Bound Bottom")
		(35 "F.Fab" user "Ref Des/Assembly Top")
		(33 "B.Fab" user "Ref Des/Assembly Bottom")
	)
	(footprint ""
		(layer "F.Cu")
		(at 166.543736 -67.564 180)
		(property "Reference" "R5895"
			(at 0 0 180)
			(layer "F.SilkS")
			(hide yes)
			(effects
				(font
					(size 1.27 1.27)
				)
			)
		)
		(property "Value" ""
			(at 0 0 180)
			(layer "F.Fab")
			(effects
				(font
					(size 1.27 1.27)
				)
			)
		)
		(duplicate_pad_numbers_are_jumpers no)
		(fp_line
			(start 0.7874 0.4064)
			(end -0.7874 0.4064)
			(stroke
				(width 0.1524)
				(type default)
			)
			(layer "F.SilkS")
		)
		(fp_line
			(start 0.7874 -0.4064)
			(end 0.7874 0.4064)
			(stroke
				(width 0.1524)
				(type default)
			)
			(layer "F.SilkS")
		)
		(fp_line
			(start -0.7874 0.4064)
			(end -0.7874 -0.4064)
			(stroke
				(width 0.1524)
				(type default)
			)
			(layer "F.SilkS")
		)
		(fp_line
			(start -0.7874 -0.4064)
			(end 0.7874 -0.4064)
			(stroke
				(width 0.1524)
				(type default)
			)
			(layer "F.SilkS")
		)
		(fp_line
			(start 0.67945 0.3048)
			(end 0.120396 0.3048)
			(stroke
				(width 0.1)
				(type default)
			)
			(layer "F.Fab")
		)
		(fp_line
			(start 0.67945 -0.3048)
			(end 0.67945 0.3048)
			(stroke
				(width 0.1)
				(type default)
			)
			(layer "F.Fab")
		)
		(fp_line
			(start 0.12065 -0.2794)
			(end 0.12065 -0.3048)
			(stroke
				(width 0.1)
				(type default)
			)
			(layer "F.Fab")
		)
		(fp_line
			(start 0.12065 -0.3048)
			(end 0.67945 -0.3048)
			(stroke
				(width 0.1)
				(type default)
			)
			(layer "F.Fab")
		)
		(fp_line
			(start 0.120396 0.3048)
			(end 0.120396 0.2794)
			(stroke
				(width 0.1)
				(type default)
			)
			(layer "F.Fab")
		)
		(fp_line
			(start 0.120396 0.2794)
			(end -0.12065 0.2794)
			(stroke
				(width 0.1)
				(type default)
			)
			(layer "F.Fab")
		)
		(fp_line
			(start -0.12065 0.3048)
			(end -0.67945 0.3048)
			(stroke
				(width 0.1)
				(type default)
			)
			(layer "F.Fab")
		)
		(fp_line
			(start -0.12065 0.2794)
			(end -0.12065 0.3048)
			(stroke
				(width 0.1)
				(type default)
			)
			(layer "F.Fab")
		)
		(fp_line
			(start -0.12065 -0.2794)
			(end 0.12065 -0.2794)
			(stroke
				(width 0.1)
				(type default)
			)
			(layer "F.Fab")
		)
		(fp_line
			(start -0.12065 -0.305054)
			(end -0.12065 -0.2794)
			(stroke
				(width 0.1)
				(type default)
			)
			(layer "F.Fab")
		)
		(fp_line
			(start -0.67945 0.3048)
			(end -0.67945 -0.305054)
			(stroke
				(width 0.1)
				(type default)
			)
			(layer "F.Fab")
		)
		(fp_line
			(start -0.67945 -0.305054)
			(end -0.12065 -0.305054)
			(stroke
				(width 0.1)
				(type default)
			)
			(layer "F.Fab")
		)
		(pad "1" smd circle
			(at -0.40005 0 180)
			(size 0 0)
			(layers "F.Cu" "F.Mask" "F.Paste")
			(net "P52V_HS2_ADR1")
		)
		(pad "2" smd circle
			(at 0.40005 0 180)
			(size 0 0)
			(layers "F.Cu" "F.Mask" "F.Paste")
			(net "GND1_FIELD_SIGNAL")
		)
	)
	(footprint ""
		(layer "F.Cu")
		(at 56.799988 -156.830014 180)
		(property "Reference" "J3"
			(at 4.983988 -7.758684 0)
			(unlocked yes)
			(layer "F.SilkS")
			(effects
				(font
					(size 0.7874 0.5842)
					(thickness 0.1524)
				)
				(justify left)
			)
		)
		(property "Value" ""
			(at 0 0 180)
			(layer "F.Fab")
			(effects
				(font
					(size 1.27 1.27)
				)
			)
		)
		(duplicate_pad_numbers_are_jumpers no)
		(fp_line
			(start 12.925044 28.450032)
			(end -4.92506 28.450032)
			(stroke
				(width 0.1524)
				(type default)
			)
			(layer "F.SilkS")
		)
		(fp_line
			(start 12.925044 -6.849872)
			(end 12.925044 28.450032)
			(stroke
				(width 0.1524)
				(type default)
			)
			(layer "F.SilkS")
		)
		(fp_line
			(start 9.92505 25.450038)
			(end -1.925066 25.450038)
			(stroke
				(width 0.1524)
				(type default)
			)
			(layer "F.SilkS")
		)
		(fp_line
			(start 9.92505 -3.850132)
			(end 9.92505 25.450038)
			(stroke
				(width 0.1524)
				(type default)
			)
			(layer "F.SilkS")
		)
		(fp_line
			(start -1.925066 25.450038)
			(end -1.925066 -3.850132)
			(stroke
				(width 0.1524)
				(type default)
			)
			(layer "F.SilkS")
		)
		(fp_line
			(start -1.925066 14.99997)
			(end 9.92505 14.99997)
			(stroke
				(width 0.1524)
				(type default)
			)
			(layer "F.SilkS")
		)
		(fp_line
			(start -1.925066 -3.850132)
			(end 9.92505 -3.850132)
			(stroke
				(width 0.1524)
				(type default)
			)
			(layer "F.SilkS")
		)
		(fp_line
			(start -4.92506 28.450032)
			(end -4.92506 -6.849872)
			(stroke
				(width 0.1524)
				(type default)
			)
			(layer "F.SilkS")
		)
		(fp_line
			(start -4.92506 -6.849872)
			(end 12.925044 -6.849872)
			(stroke
				(width 0.1524)
				(type default)
			)
			(layer "F.SilkS")
		)
		(fp_poly
			(pts
				(xy 0.045974 -1.23571) (xy 0.807974 -3.14071) (xy -0.716026 -3.14071)
			)
			(stroke
				(width 0)
				(type default)
			)
			(fill yes)
			(layer "F.SilkS")
		)
		(fp_line
			(start 12.925044 28.450032)
			(end -4.92506 28.450032)
			(stroke
				(width 0.1524)
				(type default)
			)
			(layer "B.SilkS")
		)
		(fp_line
			(start 12.925044 -6.849872)
			(end 12.925044 28.450032)
			(stroke
				(width 0.1524)
				(type default)
			)
			(layer "B.SilkS")
		)
		(fp_line
			(start -4.92506 28.450032)
			(end -4.92506 -6.849872)
			(stroke
				(width 0.1524)
				(type default)
			)
			(layer "B.SilkS")
		)
		(fp_line
			(start -4.92506 -6.849872)
			(end 12.925044 -6.849872)
			(stroke
				(width 0.1524)
				(type default)
			)
			(layer "B.SilkS")
		)
		(fp_line
			(start 12.925044 28.450032)
			(end -4.92506 28.450032)
			(stroke
				(width 0.1)
				(type default)
			)
			(layer "B.Fab")
		)
		(fp_line
			(start 12.925044 -6.849872)
			(end 12.925044 28.450032)
			(stroke
				(width 0.1)
				(type default)
			)
			(layer "B.Fab")
		)
		(fp_line
			(start -4.92506 28.450032)
			(end -4.92506 -6.849872)
			(stroke
				(width 0.1)
				(type default)
			)
			(layer "B.Fab")
		)
		(fp_line
			(start -4.92506 -6.849872)
			(end 12.925044 -6.849872)
			(stroke
				(width 0.1)
				(type default)
			)
			(layer "B.Fab")
		)
		(fp_line
			(start 9.92505 25.450038)
			(end -1.925066 25.450038)
			(stroke
				(width 0.1)
				(type default)
			)
			(layer "F.Fab")
		)
		(fp_line
			(start 9.92505 -3.850132)
			(end 9.92505 25.450038)
			(stroke
				(width 0.1)
				(type default)
			)
			(layer "F.Fab")
		)
		(fp_line
			(start -1.925066 25.450038)
			(end -1.925066 -3.850132)
			(stroke
				(width 0.1)
				(type default)
			)
			(layer "F.Fab")
		)
		(fp_line
			(start -1.925066 -3.850132)
			(end 9.92505 -3.850132)
			(stroke
				(width 0.1)
				(type default)
			)
			(layer "F.Fab")
		)
		(fp_poly
			(pts
				(xy -2.108708 0) (xy -4.013708 -0.762) (xy -4.013708 0.762)
			)
			(stroke
				(width 0)
				(type default)
			)
			(fill yes)
			(layer "F.Fab")
		)
		(fp_text user "PRESS-FIT"
			(at 7.474458 -5.30098 0)
			(unlocked yes)
			(layer "F.SilkS")
			(effects
				(font
					(size 0.7874 0.5842)
					(thickness 0.1524)
				)
				(justify left)
			)
		)
		(fp_text user "PRESS-FIT"
			(at 11.594338 -4.684014 270)
			(unlocked yes)
			(layer "B.SilkS")
			(effects
				(font
					(size 1.905 1.4224)
					(thickness 0.1524)
				)
				(justify left mirror)
			)
		)
		(fp_text user "PRESS-FIT"
			(at 11.346942 12.866116 90)
			(unlocked yes)
			(layer "B.Fab")
			(effects
				(font
					(size 1.905 1.4224)
					(thickness 0.1524)
				)
				(justify left mirror)
			)
		)
		(fp_text user "PRESS-FIT"
			(at 11.346942 -3.872484 90)
			(unlocked yes)
			(layer "F.Fab")
			(effects
				(font
					(size 1.905 1.4224)
					(thickness 0.1524)
				)
				(justify left)
			)
		)
		(pad "" np_thru_hole circle
			(at 3.999992 5.500116 180)
			(size 2.1082 2.1082)
			(drill 2.1082)
			(layers "*.Cu" "*.Mask")
			(clearance 0.381)
			(thermal_gap 0.381)
		)
		(pad "A1" thru_hole rect
			(at 0 0 180)
			(size 1.156208 1.156208)
			(drill 0.749808)
			(layers "*.Cu" "*.Mask")
			(remove_unused_layers no)
			(net "P52V_HS2")
			(clearance 0.0508)
			(thermal_gap 0.0508)
			(padstack
				(mode front_inner_back)
				(layer "Inner"
					(shape circle)
					(size 1.156208 1.156208)
					(clearance 0.0508)
				)
				(layer "B.Cu"
					(shape rect)
					(size 1.156208 1.156208)
					(clearance 0.0508)
				)
			)
		)
		(pad "A2" thru_hole circle
			(at 0 1.999996 180)
			(size 1.156208 1.156208)
			(drill 0.749808)
			(layers "*.Cu" "*.Mask")
			(remove_unused_layers no)
			(net "P52V_HS2")
			(clearance 0.0508)
			(thermal_gap 0.0508)
		)
		(pad "A3" thru_hole circle
			(at 0 3.999992 180)
			(size 1.156208 1.156208)
			(drill 0.749808)
			(layers "*.Cu" "*.Mask")
			(remove_unused_layers no)
			(net "P52V_HS2")
			(clearance 0.0508)
			(thermal_gap 0.0508)
		)
		(pad "A4" thru_hole circle
			(at 1.999996 0 180)
			(size 1.156208 1.156208)
			(drill 0.749808)
			(layers "*.Cu" "*.Mask")
			(remove_unused_layers no)
			(net "P52V_HS2")
			(clearance 0.0508)
			(thermal_gap 0.0508)
		)
		(pad "A5" thru_hole circle
			(at 1.999996 1.999996 180)
			(size 1.156208 1.156208)
			(drill 0.749808)
			(layers "*.Cu" "*.Mask")
			(remove_unused_layers no)
			(net "P52V_HS2")
			(clearance 0.0508)
			(thermal_gap 0.0508)
		)
		(pad "A6" thru_hole circle
			(at 1.999996 3.999992 180)
			(size 1.156208 1.156208)
			(drill 0.749808)
			(layers "*.Cu" "*.Mask")
			(remove_unused_layers no)
			(net "P52V_HS2")
			(clearance 0.0508)
			(thermal_gap 0.0508)
		)
		(pad "B1" thru_hole circle
			(at 7.999984 0 180)
			(size 1.156208 1.156208)
			(drill 0.749808)
			(layers "*.Cu" "*.Mask")
			(remove_unused_layers no)
			(net "P52V_HS2")
			(clearance 0.0508)
			(thermal_gap 0.0508)
		)
		(pad "B2" thru_hole circle
			(at 7.999984 1.999996 180)
			(size 1.156208 1.156208)
			(drill 0.749808)
			(layers "*.Cu" "*.Mask")
			(remove_unused_layers no)
			(net "P52V_HS2")
			(clearance 0.0508)
			(thermal_gap 0.0508)
		)
		(pad "B3" thru_hole circle
			(at 7.999984 3.999992 180)
			(size 1.156208 1.156208)
			(drill 0.749808)
			(layers "*.Cu" "*.Mask")
			(remove_unused_layers no)
			(net "P52V_HS2")
			(clearance 0.0508)
			(thermal_gap 0.0508)
		)
		(pad "B4" thru_hole circle
			(at 5.999988 0 180)
			(size 1.156208 1.156208)
			(drill 0.749808)
			(layers "*.Cu" "*.Mask")
			(remove_unused_layers no)
			(net "P52V_HS2")
			(clearance 0.0508)
			(thermal_gap 0.0508)
		)
		(pad "B5" thru_hole circle
			(at 5.999988 1.999996 180)
			(size 1.156208 1.156208)
			(drill 0.749808)
			(layers "*.Cu" "*.Mask")
			(remove_unused_layers no)
			(net "P52V_HS2")
			(clearance 0.0508)
			(thermal_gap 0.0508)
		)
		(pad "B6" thru_hole circle
			(at 5.999988 3.999992 180)
			(size 1.156208 1.156208)
			(drill 0.749808)
			(layers "*.Cu" "*.Mask")
			(remove_unused_layers no)
			(net "P52V_HS2")
			(clearance 0.0508)
			(thermal_gap 0.0508)
		)
		(pad "C1" thru_hole circle
			(at 7.999984 7.999984 180)
			(size 1.156208 1.156208)
			(drill 0.749808)
			(layers "*.Cu" "*.Mask")
			(remove_unused_layers no)
			(net "GND")
			(clearance 0.0508)
			(thermal_gap 0.0508)
		)
		(pad "C2" thru_hole circle
			(at 7.999984 9.99998 180)
			(size 1.156208 1.156208)
			(drill 0.749808)
			(layers "*.Cu" "*.Mask")
			(remove_unused_layers no)
			(net "GND")
			(clearance 0.0508)
			(thermal_gap 0.0508)
		)
		(pad "C3" thru_hole circle
			(at 7.999984 11.999976 180)
			(size 1.156208 1.156208)
			(drill 0.749808)
			(layers "*.Cu" "*.Mask")
			(remove_unused_layers no)
			(net "GND")
			(clearance 0.0508)
			(thermal_gap 0.0508)
		)
		(pad "C4" thru_hole circle
			(at 5.999988 7.999984 180)
			(size 1.156208 1.156208)
			(drill 0.749808)
			(layers "*.Cu" "*.Mask")
			(remove_unused_layers no)
			(net "GND")
			(clearance 0.0508)
			(thermal_gap 0.0508)
		)
		(pad "C5" thru_hole circle
			(at 5.999988 9.99998 180)
			(size 1.156208 1.156208)
			(drill 0.749808)
			(layers "*.Cu" "*.Mask")
			(remove_unused_layers no)
			(net "GND")
			(clearance 0.0508)
			(thermal_gap 0.0508)
		)
		(pad "C6" thru_hole circle
			(at 5.999988 11.999976 180)
			(size 1.156208 1.156208)
			(drill 0.749808)
			(layers "*.Cu" "*.Mask")
			(remove_unused_layers no)
			(net "GND")
			(clearance 0.0508)
			(thermal_gap 0.0508)
		)
		(pad "D1" thru_hole circle
			(at 0 7.999984 180)
			(size 1.156208 1.156208)
			(drill 0.749808)
			(layers "*.Cu" "*.Mask")
			(remove_unused_layers no)
			(net "GND")
			(clearance 0.0508)
			(thermal_gap 0.0508)
		)
		(pad "D2" thru_hole circle
			(at 0 9.99998 180)
			(size 1.156208 1.156208)
			(drill 0.749808)
			(layers "*.Cu" "*.Mask")
			(remove_unused_layers no)
			(net "GND")
			(clearance 0.0508)
			(thermal_gap 0.0508)
		)
		(pad "D3" thru_hole circle
			(at 0 11.999976 180)
			(size 1.156208 1.156208)
			(drill 0.749808)
			(layers "*.Cu" "*.Mask")
			(remove_unused_layers no)
			(net "GND")
			(clearance 0.0508)
			(thermal_gap 0.0508)
		)
		(pad "D4" thru_hole circle
			(at 1.999996 7.999984 180)
			(size 1.156208 1.156208)
			(drill 0.749808)
			(layers "*.Cu" "*.Mask")
			(remove_unused_layers no)
			(net "GND")
			(clearance 0.0508)
			(thermal_gap 0.0508)
		)
		(pad "D5" thru_hole circle
			(at 1.999996 9.99998 180)
			(size 1.156208 1.156208)
			(drill 0.749808)
			(layers "*.Cu" "*.Mask")
			(remove_unused_layers no)
			(net "GND")
			(clearance 0.0508)
			(thermal_gap 0.0508)
		)
		(pad "D6" thru_hole circle
			(at 1.999996 11.999976 180)
			(size 1.156208 1.156208)
			(drill 0.749808)
			(layers "*.Cu" "*.Mask")
			(remove_unused_layers no)
			(net "GND")
			(clearance 0.0508)
			(thermal_gap 0.0508)
		)
		(zone
			(layers "F.Cu" "B.Cu" "In1.Cu" "In2.Cu" "In3.Cu" "In4.Cu" "In5.Cu" "In6.Cu"
				"In7.Cu" "In8.Cu"
			)
			(hatch none 0.5)
			(connect_pads
				(clearance 0)
			)
			(min_thickness 0.25)
			(keepout
				(tracks not_allowed)
				(vias allowed)
				(pads allowed)
				(copperpour not_allowed)
				(footprints allowed)
			)
			(placement
				(enabled no)
				(sheetname "")
			)
			(fill
				(thermal_gap 0.5)
				(thermal_bridge_width 0.5)
				(island_removal_mode 0)
			)
			(polygon
				(pts
					(arc
						(start 54.260496 -162.329876)
						(mid 51.339496 -162.330384)
						(end 54.260496 -162.329876)
					)
				)
			)
		)
		(zone
			(layer "B.Cu")
			(hatch none 0.5)
			(connect_pads
				(clearance 0)
			)
			(min_thickness 0.25)
			(keepout
				(tracks allowed)
				(vias not_allowed)
				(pads allowed)
				(copperpour not_allowed)
				(footprints allowed)
			)
			(placement
				(enabled no)
				(sheetname "")
			)
			(fill
				(thermal_gap 0.5)
				(thermal_bridge_width 0.5)
				(island_removal_mode 0)
			)
			(polygon
				(pts
					(xy 51.441096 -169.46753) (xy 48.164496 -169.46753) (xy 48.164496 -164.18433) (xy 51.441096 -164.18433)
				)
			)
		)
		(zone
			(layer "B.Cu")
			(hatch none 0.5)
			(connect_pads
				(clearance 0)
			)
			(min_thickness 0.25)
			(keepout
				(tracks allowed)
				(vias not_allowed)
				(pads allowed)
				(copperpour not_allowed)
				(footprints allowed)
			)
			(placement
				(enabled no)
				(sheetname "")
			)
			(fill
				(thermal_gap 0.5)
				(thermal_bridge_width 0.5)
				(island_removal_mode 0)
			)
			(polygon
				(pts
					(xy 51.441096 -161.46653) (xy 48.164496 -161.46653) (xy 48.164496 -156.18333) (xy 51.441096 -156.18333)
				)
			)
		)
		(zone
			(layer "B.Cu")
			(hatch none 0.5)
			(connect_pads
				(clearance 0)
			)
			(min_thickness 0.25)
			(keepout
				(tracks allowed)
				(vias not_allowed)
				(pads allowed)
				(copperpour not_allowed)
				(footprints allowed)
			)
			(placement
				(enabled no)
				(sheetname "")
			)
			(fill
				(thermal_gap 0.5)
				(thermal_bridge_width 0.5)
				(island_removal_mode 0)
			)
			(polygon
				(pts
					(xy 57.435496 -169.46753) (xy 54.158896 -169.46753) (xy 54.158896 -164.18433) (xy 57.435496 -164.18433)
				)
			)
		)
		(zone
			(layer "B.Cu")
			(hatch none 0.5)
			(connect_pads
				(clearance 0)
			)
			(min_thickness 0.25)
			(keepout
				(tracks allowed)
				(vias not_allowed)
				(pads allowed)
				(copperpour not_allowed)
				(footprints allowed)
			)
			(placement
				(enabled no)
				(sheetname "")
			)
			(fill
				(thermal_gap 0.5)
				(thermal_bridge_width 0.5)
				(island_removal_mode 0)
			)
			(polygon
				(pts
					(xy 57.435496 -161.46653) (xy 54.158896 -161.46653) (xy 54.158896 -156.18333) (xy 57.435496 -156.18333)
				)
			)
		)
	)
)
